# T6G (Grand Teton) — schematic netlist excerpt (pin names and nets, part order shuffled) for the footprints in the layout excerpt that follows; sources: Cadence DE-HDL packaged netlist, KiCad conversion of 04192023_DAF0TMB3IC0_F0TG_MB_C_brd_V02_OCP.brd

PL6505  Q_INDUCTOR  120NH/69A IND  pkg SMLF  page 363 : \1\ = SW_P0V9_RETIMER_CPU0_SW1 ; \2\ = P0V9_CPU0_RT_2D
R594  Q_RES  10K 1% CHIP  pkg 0402LF  page 183 : A = FM_9ZXL045_P1_0_OE_N ; B = GND
C1503  Q_CAP  0.1UF 16V 10% X7R  pkg C0402  page 172 : A = P3V3_AUX ; B = GND

(kicad_pcb
	(version 20260206)
	(generator "pcbnew")
	(generator_version "10.0")
	(general
		(thickness 1.6)
		(legacy_teardrops no)
	)
	(paper "A4")
	(title_block
		(title "04192023_DAF0TMB3IC0_F0TG_MB_C_brd_V02_OCP.brd")
		(comment 1 "Grand Teton / footprints 82-84 of 8354")
	)
	(layers
		(0 "F.Cu" signal "TOP")
		(4 "In1.Cu" signal "GND")
		(6 "In2.Cu" signal "IN1")
		(8 "In3.Cu" signal "GND1")
		(10 "In4.Cu" signal "IN2")
		(12 "In5.Cu" signal "GND2")
		(14 "In6.Cu" signal "IN3")
		(16 "In7.Cu" signal "GND3")
		(18 "In8.Cu" signal "VCC")
		(20 "In9.Cu" signal "VCC1")
		(22 "In10.Cu" signal "GND4")
		(24 "In11.Cu" signal "IN4")
		(26 "In12.Cu" signal "GND5")
		(28 "In13.Cu" signal "IN5")
		(30 "In14.Cu" signal "GND6")
		(32 "In15.Cu" signal "IN6")
		(34 "In16.Cu" signal "GND7")
		(2 "B.Cu" signal "BOTTOM")
		(9 "F.Adhes" user "F.Adhesive")
		(11 "B.Adhes" user "B.Adhesive")
		(13 "F.Paste" user "Package Geometry/Pastemask Top")
		(15 "B.Paste" user "Package Geometry/Pastemask Bottom")
		(5 "F.SilkS" user "Ref Des/Silkscreen Top")
		(7 "B.SilkS" user "Ref Des/Silkscreen Bottom")
		(1 "F.Mask" user "Board Geometry/Soldermask Top")
		(3 "B.Mask" user "Board Geometry/Soldermask Bottom")
		(17 "Dwgs.User" user "User.Drawings")
		(19 "Cmts.User" user "User.Comments")
		(21 "Eco1.User" user "User.Eco1")
		(23 "Eco2.User" user "User.Eco2")
		(25 "Edge.Cuts" user "Board Geometry/Outline")
		(27 "Margin" user)
		(31 "F.CrtYd" user "Package Geometry/Place Bound Top")
		(29 "B.CrtYd" user "Package Geometry/Place Bound Bottom")
		(35 "F.Fab" user "Ref Des/Assembly Top")
		(33 "B.Fab" user "Ref Des/Assembly Bottom")
	)
	(footprint ""
		(layer "F.Cu")
		(at 100.48367 -407.167588 180)
		(property "Reference" "R594"
			(at 0 0 180)
			(layer "F.SilkS")
			(hide yes)
			(effects
				(font
					(size 1.27 1.27)
				)
			)
		)
		(property "Value" ""
			(at 0 0 180)
			(layer "F.Fab")
			(effects
				(font
					(size 1.27 1.27)
				)
			)
		)
		(duplicate_pad_numbers_are_jumpers no)
		(fp_line
			(start 0.7874 0.4064)
			(end -0.7874 0.4064)
			(stroke
				(width 0.1524)
				(type default)
			)
			(layer "F.SilkS")
		)
		(fp_line
			(start 0.7874 -0.4064)
			(end 0.7874 0.4064)
			(stroke
				(width 0.1524)
				(type default)
			)
			(layer "F.SilkS")
		)
		(fp_line
			(start -0.7874 0.4064)
			(end -0.7874 -0.4064)
			(stroke
				(width 0.1524)
				(type default)
			)
			(layer "F.SilkS")
		)
		(fp_line
			(start -0.7874 -0.4064)
			(end 0.7874 -0.4064)
			(stroke
				(width 0.1524)
				(type default)
			)
			(layer "F.SilkS")
		)
		(fp_line
			(start 0.67945 0.3048)
			(end 0.120396 0.3048)
			(stroke
				(width 0.1)
				(type default)
			)
			(layer "F.Fab")
		)
		(fp_line
			(start 0.67945 -0.3048)
			(end 0.67945 0.3048)
			(stroke
				(width 0.1)
				(type default)
			)
			(layer "F.Fab")
		)
		(fp_line
			(start 0.12065 -0.2794)
			(end 0.12065 -0.3048)
			(stroke
				(width 0.1)
				(type default)
			)
			(layer "F.Fab")
		)
		(fp_line
			(start 0.12065 -0.3048)
			(end 0.67945 -0.3048)
			(stroke
				(width 0.1)
				(type default)
			)
			(layer "F.Fab")
		)
		(fp_line
			(start 0.120396 0.3048)
			(end 0.120396 0.2794)
			(stroke
				(width 0.1)
				(type default)
			)
			(layer "F.Fab")
		)
		(fp_line
			(start 0.120396 0.2794)
			(end -0.12065 0.2794)
			(stroke
				(width 0.1)
				(type default)
			)
			(layer "F.Fab")
		)
		(fp_line
			(start -0.12065 0.3048)
			(end -0.67945 0.3048)
			(stroke
				(width 0.1)
				(type default)
			)
			(layer "F.Fab")
		)
		(fp_line
			(start -0.12065 0.2794)
			(end -0.12065 0.3048)
			(stroke
				(width 0.1)
				(type default)
			)
			(layer "F.Fab")
		)
		(fp_line
			(start -0.12065 -0.2794)
			(end 0.12065 -0.2794)
			(stroke
				(width 0.1)
				(type default)
			)
			(layer "F.Fab")
		)
		(fp_line
			(start -0.12065 -0.305054)
			(end -0.12065 -0.2794)
			(stroke
				(width 0.1)
				(type default)
			)
			(layer "F.Fab")
		)
		(fp_line
			(start -0.67945 0.3048)
			(end -0.67945 -0.305054)
			(stroke
				(width 0.1)
				(type default)
			)
			(layer "F.Fab")
		)
		(fp_line
			(start -0.67945 -0.305054)
			(end -0.12065 -0.305054)
			(stroke
				(width 0.1)
				(type default)
			)
			(layer "F.Fab")
		)
		(pad "1" smd circle
			(at -0.40005 0 180)
			(size 0 0)
			(layers "F.Cu" "F.Mask" "F.Paste")
			(net "FM_9ZXL045_P1_0_OE_N")
		)
		(pad "2" smd circle
			(at 0.40005 0 180)
			(size 0 0)
			(layers "F.Cu" "F.Mask" "F.Paste")
			(net "GND")
		)
	)
	(footprint ""
		(layer "F.Cu")
		(at 146.776186 -54.913784 -90)
		(property "Reference" "C1503"
			(at 0 0 270)
			(layer "F.SilkS")
			(hide yes)
			(effects
				(font
					(size 1.27 1.27)
				)
			)
		)
		(property "Value" ""
			(at 0 0 270)
			(layer "F.Fab")
			(effects
				(font
					(size 1.27 1.27)
				)
			)
		)
		(duplicate_pad_numbers_are_jumpers no)
		(fp_line
			(start -0.7874 0.4064)
			(end -0.7874 -0.4064)
			(stroke
				(width 0.1524)
				(type default)
			)
			(layer "F.SilkS")
		)
		(fp_line
			(start 0.7874 0.4064)
			(end -0.7874 0.4064)
			(stroke
				(width 0.1524)
				(type default)
			)
			(layer "F.SilkS")
		)
		(fp_line
			(start -0.7874 -0.4064)
			(end 0.7874 -0.4064)
			(stroke
				(width 0.1524)
				(type default)
			)
			(layer "F.SilkS")
		)
		(fp_line
			(start 0.7874 -0.4064)
			(end 0.7874 0.4064)
			(stroke
				(width 0.1524)
				(type default)
			)
			(layer "F.SilkS")
		)
		(fp_line
			(start -0.67945 0.3048)
			(end -0.67945 -0.305054)
			(stroke
				(width 0.1)
				(type default)
			)
			(layer "F.Fab")
		)
		(fp_line
			(start -0.12065 0.3048)
			(end -0.67945 0.3048)
			(stroke
				(width 0.1)
				(type default)
			)
			(layer "F.Fab")
		)
		(fp_line
			(start 0.120396 0.3048)
			(end 0.120396 0.2794)
			(stroke
				(width 0.1)
				(type default)
			)
			(layer "F.Fab")
		)
		(fp_line
			(start 0.67945 0.3048)
			(end 0.120396 0.3048)
			(stroke
				(width 0.1)
				(type default)
			)
			(layer "F.Fab")
		)
		(fp_line
			(start -0.12065 0.2794)
			(end -0.12065 0.3048)
			(stroke
				(width 0.1)
				(type default)
			)
			(layer "F.Fab")
		)
		(fp_line
			(start 0.120396 0.2794)
			(end -0.12065 0.2794)
			(stroke
				(width 0.1)
				(type default)
			)
			(layer "F.Fab")
		)
		(fp_line
			(start -0.12065 -0.2794)
			(end 0.12065 -0.2794)
			(stroke
				(width 0.1)
				(type default)
			)
			(layer "F.Fab")
		)
		(fp_line
			(start 0.12065 -0.2794)
			(end 0.12065 -0.3048)
			(stroke
				(width 0.1)
				(type default)
			)
			(layer "F.Fab")
		)
		(fp_line
			(start 0.12065 -0.3048)
			(end 0.67945 -0.3048)
			(stroke
				(width 0.1)
				(type default)
			)
			(layer "F.Fab")
		)
		(fp_line
			(start 0.67945 -0.3048)
			(end 0.67945 0.3048)
			(stroke
				(width 0.1)
				(type default)
			)
			(layer "F.Fab")
		)
		(fp_line
			(start -0.67945 -0.305054)
			(end -0.12065 -0.305054)
			(stroke
				(width 0.1)
				(type default)
			)
			(layer "F.Fab")
		)
		(fp_line
			(start -0.12065 -0.305054)
			(end -0.12065 -0.2794)
			(stroke
				(width 0.1)
				(type default)
			)
			(layer "F.Fab")
		)
		(pad "1" smd circle
			(at -0.40005 0 270)
			(size 0 0)
			(layers "F.Cu" "F.Mask" "F.Paste")
			(net "P3V3_AUX")
		)
		(pad "2" smd circle
			(at 0.40005 0 270)
			(size 0 0)
			(layers "F.Cu" "F.Mask" "F.Paste")
			(net "GND")
		)
	)
	(footprint ""
		(layer "F.Cu")
		(at 446.634616 -390.076944 -90)
		(property "Reference" "PL6505"
			(at 1.075944 -11.862054 90)
			(unlocked yes)
			(layer "F.SilkS")
			(effects
				(font
					(size 0.7874 0.5842)
					(thickness 0.1524)
				)
				(justify left)
			)
		)
		(property "Value" ""
			(at 0 0 270)
			(layer "F.Fab")
			(effects
				(font
					(size 1.27 1.27)
				)
			)
		)
		(duplicate_pad_numbers_are_jumpers no)
		(fp_line
			(start -3.24993 3.24993)
			(end -3.24993 2.2352)
			(stroke
				(width 0.1524)
				(type default)
			)
			(layer "F.SilkS")
		)
		(fp_line
			(start 3.24993 3.24993)
			(end -3.24993 3.24993)
			(stroke
				(width 0.1524)
				(type default)
			)
			(layer "F.SilkS")
		)
		(fp_line
			(start 3.24993 2.2352)
			(end 3.24993 3.24993)
			(stroke
				(width 0.1524)
				(type default)
			)
			(layer "F.SilkS")
		)
		(fp_line
			(start -3.24993 -2.2352)
			(end -3.24993 -3.24993)
			(stroke
				(width 0.1524)
				(type default)
			)
			(layer "F.SilkS")
		)
		(fp_line
			(start -3.24993 -3.24993)
			(end 3.24993 -3.24993)
			(stroke
				(width 0.1524)
				(type default)
			)
			(layer "F.SilkS")
		)
		(fp_line
			(start 3.24993 -3.24993)
			(end 3.24993 -2.2352)
			(stroke
				(width 0.1524)
				(type default)
			)
			(layer "F.SilkS")
		)
		(fp_line
			(start -3.24993 3.24993)
			(end -3.24993 -3.24993)
			(stroke
				(width 0.1)
				(type default)
			)
			(layer "F.Fab")
		)
		(fp_line
			(start 3.24993 3.24993)
			(end -3.24993 3.24993)
			(stroke
				(width 0.1)
				(type default)
			)
			(layer "F.Fab")
		)
		(fp_line
			(start -3.24993 -3.24993)
			(end 3.24993 -3.24993)
			(stroke
				(width 0.1)
				(type default)
			)
			(layer "F.Fab")
		)
		(fp_line
			(start 3.24993 -3.24993)
			(end 3.24993 3.24993)
			(stroke
				(width 0.1)
				(type default)
			)
			(layer "F.Fab")
		)
		(pad "1" smd rect
			(at -2.29997 0 270)
			(size 2.0066 4.2164)
			(layers "F.Cu" "F.Mask" "F.Paste")
			(net "SW_P0V9_RETIMER_CPU0_SW1")
		)
		(pad "2" smd rect
			(at 2.29997 0 270)
			(size 2.0066 4.2164)
			(layers "F.Cu" "F.Mask" "F.Paste")
			(net "P0V9_CPU0_RT_2D")
		)
	)
)
